(kicad_pcb
	(version 20260206)
	(generator "pcbnew")
	(generator_version "10.0")
	(general
		(thickness 1.6)
		(legacy_teardrops no)
	)
	(paper "A4")
	(title_block
		(title "01162023_DA0F0TEBIF0_F0T_Expander_BD_F_brd_V02_OCP.brd")
		(comment 1 "Grand Teton / footprints 425-429 of 9728")
	)
	(layers
		(0 "F.Cu" signal "TOP")
		(4 "In1.Cu" signal "GND")
		(6 "In2.Cu" signal "VCC")
		(8 "In3.Cu" signal "VCC1")
		(10 "In4.Cu" signal "GND1")
		(12 "In5.Cu" signal "IN1")
		(14 "In6.Cu" signal "GND2")
		(16 "In7.Cu" signal "IN2")
		(18 "In8.Cu" signal "GND3")
		(20 "In9.Cu" signal "IN3")
		(22 "In10.Cu" signal "GND4")
		(24 "In11.Cu" signal "IN4")
		(26 "In12.Cu" signal "GND5")
		(28 "In13.Cu" signal "IN5")
		(30 "In14.Cu" signal "GND6")
		(32 "In15.Cu" signal "IN6")
		(34 "In16.Cu" signal "GND7")
		(2 "B.Cu" signal "BOTTOM")
		(9 "F.Adhes" user "F.Adhesive")
		(11 "B.Adhes" user "B.Adhesive")
		(13 "F.Paste" user "Package Geometry/Pastemask Top")
		(15 "B.Paste" user "Package Geometry/Pastemask Bottom")
		(5 "F.SilkS" user "Ref Des/Silkscreen Top")
		(7 "B.SilkS" user "Ref Des/Silkscreen Bottom")
		(1 "F.Mask" user "Board Geometry/Soldermask Top")
		(3 "B.Mask" user "Board Geometry/Soldermask Bottom")
		(17 "Dwgs.User" user "User.Drawings")
		(19 "Cmts.User" user "User.Comments")
		(21 "Eco1.User" user "User.Eco1")
		(23 "Eco2.User" user "User.Eco2")
		(25 "Edge.Cuts" user "Board Geometry/Outline")
		(27 "Margin" user)
		(31 "F.CrtYd" user "Package Geometry/Place Bound Top")
		(29 "B.CrtYd" user "Package Geometry/Place Bound Bottom")
		(35 "F.Fab" user "Ref Des/Assembly Top")
		(33 "B.Fab" user "Ref Des/Assembly Bottom")
	)
	(footprint ""
		(layer "F.Cu")
		(at 220.36786 -54.067456)
		(property "Reference" "PR222"
			(at 0 0 0)
			(layer "F.SilkS")
			(hide yes)
			(effects
				(font
					(size 1.27 1.27)
				)
			)
		)
		(property "Value" ""
			(at 0 0 0)
			(layer "F.Fab")
			(effects
				(font
					(size 1.27 1.27)
				)
			)
		)
		(duplicate_pad_numbers_are_jumpers no)
		(fp_line
			(start -0.7874 -0.4064)
			(end 0.7874 -0.4064)
			(stroke
				(width 0.1524)
				(type default)
			)
			(layer "F.SilkS")
		)
		(fp_line
			(start -0.7874 0.4064)
			(end -0.7874 -0.4064)
			(stroke
				(width 0.1524)
				(type default)
			)
			(layer "F.SilkS")
		)
		(fp_line
			(start 0.7874 -0.4064)
			(end 0.7874 0.4064)
			(stroke
				(width 0.1524)
				(type default)
			)
			(layer "F.SilkS")
		)
		(fp_line
			(start 0.7874 0.4064)
			(end -0.7874 0.4064)
			(stroke
				(width 0.1524)
				(type default)
			)
			(layer "F.SilkS")
		)
		(fp_line
			(start -0.67945 -0.305054)
			(end -0.12065 -0.305054)
			(stroke
				(width 0.1)
				(type default)
			)
			(layer "F.Fab")
		)
		(fp_line
			(start -0.67945 0.3048)
			(end -0.67945 -0.305054)
			(stroke
				(width 0.1)
				(type default)
			)
			(layer "F.Fab")
		)
		(fp_line
			(start -0.12065 -0.305054)
			(end -0.12065 -0.2794)
			(stroke
				(width 0.1)
				(type default)
			)
			(layer "F.Fab")
		)
		(fp_line
			(start -0.12065 -0.2794)
			(end 0.12065 -0.2794)
			(stroke
				(width 0.1)
				(type default)
			)
			(layer "F.Fab")
		)
		(fp_line
			(start -0.12065 0.2794)
			(end -0.12065 0.3048)
			(stroke
				(width 0.1)
				(type default)
			)
			(layer "F.Fab")
		)
		(fp_line
			(start -0.12065 0.3048)
			(end -0.67945 0.3048)
			(stroke
				(width 0.1)
				(type default)
			)
			(layer "F.Fab")
		)
		(fp_line
			(start 0.120396 0.2794)
			(end -0.12065 0.2794)
			(stroke
				(width 0.1)
				(type default)
			)
			(layer "F.Fab")
		)
		(fp_line
			(start 0.120396 0.3048)
			(end 0.120396 0.2794)
			(stroke
				(width 0.1)
				(type default)
			)
			(layer "F.Fab")
		)
		(fp_line
			(start 0.12065 -0.3048)
			(end 0.67945 -0.3048)
			(stroke
				(width 0.1)
				(type default)
			)
			(layer "F.Fab")
		)
		(fp_line
			(start 0.12065 -0.2794)
			(end 0.12065 -0.3048)
			(stroke
				(width 0.1)
				(type default)
			)
			(layer "F.Fab")
		)
		(fp_line
			(start 0.67945 -0.3048)
			(end 0.67945 0.3048)
			(stroke
				(width 0.1)
				(type default)
			)
			(layer "F.Fab")
		)
		(fp_line
			(start 0.67945 0.3048)
			(end 0.120396 0.3048)
			(stroke
				(width 0.1)
				(type default)
			)
			(layer "F.Fab")
		)
		(pad "1" smd circle
			(at -0.40005 0)
			(size 0 0)
			(layers "F.Cu" "F.Mask" "F.Paste")
			(net "P12V_SSD7_OCP")
		)
		(pad "2" smd circle
			(at 0.40005 0)
			(size 0 0)
			(layers "F.Cu" "F.Mask" "F.Paste")
			(net "GND")
		)
	)
	(footprint ""
		(layer "F.Cu")
		(at 204.595984 -310.509412 135)
		(property "Reference" "R1305"
			(at 0 0 135)
			(layer "F.SilkS")
			(hide yes)
			(effects
				(font
					(size 1.27 1.27)
				)
			)
		)
		(property "Value" ""
			(at 0 0 135)
			(layer "F.Fab")
			(effects
				(font
					(size 1.27 1.27)
				)
			)
		)
		(duplicate_pad_numbers_are_jumpers no)
		(fp_line
			(start 0.787389 -0.406267)
			(end 0.787389 0.406267)
			(stroke
				(width 0.1524)
				(type default)
			)
			(layer "F.SilkS")
		)
		(fp_line
			(start 0.787389 0.406267)
			(end -0.787389 0.406267)
			(stroke
				(width 0.1524)
				(type default)
			)
			(layer "F.SilkS")
		)
		(fp_line
			(start -0.787389 -0.406267)
			(end 0.787389 -0.406267)
			(stroke
				(width 0.1524)
				(type default)
			)
			(layer "F.SilkS")
		)
		(fp_line
			(start -0.787389 0.406267)
			(end -0.787389 -0.406267)
			(stroke
				(width 0.1524)
				(type default)
			)
			(layer "F.SilkS")
		)
		(fp_line
			(start 0.679446 -0.30479)
			(end 0.679446 0.30479)
			(stroke
				(width 0.1)
				(type default)
			)
			(layer "F.Fab")
		)
		(fp_line
			(start 0.120515 -0.30479)
			(end 0.679446 -0.30479)
			(stroke
				(width 0.1)
				(type default)
			)
			(layer "F.Fab")
		)
		(fp_line
			(start 0.120695 -0.279466)
			(end 0.120515 -0.30479)
			(stroke
				(width 0.1)
				(type default)
			)
			(layer "F.Fab")
		)
		(fp_line
			(start 0.679446 0.30479)
			(end 0.120515 0.30479)
			(stroke
				(width 0.1)
				(type default)
			)
			(layer "F.Fab")
		)
		(fp_line
			(start -0.120695 -0.304969)
			(end -0.120695 -0.279466)
			(stroke
				(width 0.1)
				(type default)
			)
			(layer "F.Fab")
		)
		(fp_line
			(start -0.120695 -0.279466)
			(end 0.120695 -0.279466)
			(stroke
				(width 0.1)
				(type default)
			)
			(layer "F.Fab")
		)
		(fp_line
			(start 0.120335 0.279466)
			(end -0.120695 0.279466)
			(stroke
				(width 0.1)
				(type default)
			)
			(layer "F.Fab")
		)
		(fp_line
			(start 0.120515 0.30479)
			(end 0.120335 0.279466)
			(stroke
				(width 0.1)
				(type default)
			)
			(layer "F.Fab")
		)
		(fp_line
			(start -0.679446 -0.305149)
			(end -0.120695 -0.304969)
			(stroke
				(width 0.1)
				(type default)
			)
			(layer "F.Fab")
		)
		(fp_line
			(start -0.120695 0.279466)
			(end -0.120515 0.30479)
			(stroke
				(width 0.1)
				(type default)
			)
			(layer "F.Fab")
		)
		(fp_line
			(start -0.120515 0.30479)
			(end -0.679446 0.30479)
			(stroke
				(width 0.1)
				(type default)
			)
			(layer "F.Fab")
		)
		(fp_line
			(start -0.679446 0.30479)
			(end -0.679446 -0.305149)
			(stroke
				(width 0.1)
				(type default)
			)
			(layer "F.Fab")
		)
		(pad "1" smd circle
			(at -0.40005 0 135)
			(size 0 0)
			(layers "F.Cu" "F.Mask" "F.Paste")
			(net "PEX1_SPARE2")
		)
		(pad "2" smd circle
			(at 0.40005 0 135)
			(size 0 0)
			(layers "F.Cu" "F.Mask" "F.Paste")
			(net "P1V8_PEX")
		)
	)
	(footprint ""
		(layer "F.Cu")
		(at 32.31769 -115.336574 90)
		(property "Reference" "R43"
			(at 0 0 90)
			(layer "F.SilkS")
			(hide yes)
			(effects
				(font
					(size 1.27 1.27)
				)
			)
		)
		(property "Value" ""
			(at 0 0 90)
			(layer "F.Fab")
			(effects
				(font
					(size 1.27 1.27)
				)
			)
		)
		(duplicate_pad_numbers_are_jumpers no)
		(fp_line
			(start 0.7874 -0.4064)
			(end 0.7874 0.4064)
			(stroke
				(width 0.1524)
				(type default)
			)
			(layer "F.SilkS")
		)
		(fp_line
			(start -0.7874 -0.4064)
			(end 0.7874 -0.4064)
			(stroke
				(width 0.1524)
				(type default)
			)
			(layer "F.SilkS")
		)
		(fp_line
			(start 0.7874 0.4064)
			(end -0.7874 0.4064)
			(stroke
				(width 0.1524)
				(type default)
			)
			(layer "F.SilkS")
		)
		(fp_line
			(start -0.7874 0.4064)
			(end -0.7874 -0.4064)
			(stroke
				(width 0.1524)
				(type default)
			)
			(layer "F.SilkS")
		)
		(fp_line
			(start -0.12065 -0.305054)
			(end -0.12065 -0.2794)
			(stroke
				(width 0.1)
				(type default)
			)
			(layer "F.Fab")
		)
		(fp_line
			(start -0.67945 -0.305054)
			(end -0.12065 -0.305054)
			(stroke
				(width 0.1)
				(type default)
			)
			(layer "F.Fab")
		)
		(fp_line
			(start 0.67945 -0.3048)
			(end 0.67945 0.3048)
			(stroke
				(width 0.1)
				(type default)
			)
			(layer "F.Fab")
		)
		(fp_line
			(start 0.12065 -0.3048)
			(end 0.67945 -0.3048)
			(stroke
				(width 0.1)
				(type default)
			)
			(layer "F.Fab")
		)
		(fp_line
			(start 0.12065 -0.2794)
			(end 0.12065 -0.3048)
			(stroke
				(width 0.1)
				(type default)
			)
			(layer "F.Fab")
		)
		(fp_line
			(start -0.12065 -0.2794)
			(end 0.12065 -0.2794)
			(stroke
				(width 0.1)
				(type default)
			)
			(layer "F.Fab")
		)
		(fp_line
			(start 0.120396 0.2794)
			(end -0.12065 0.2794)
			(stroke
				(width 0.1)
				(type default)
			)
			(layer "F.Fab")
		)
		(fp_line
			(start -0.12065 0.2794)
			(end -0.12065 0.3048)
			(stroke
				(width 0.1)
				(type default)
			)
			(layer "F.Fab")
		)
		(fp_line
			(start 0.67945 0.3048)
			(end 0.120396 0.3048)
			(stroke
				(width 0.1)
				(type default)
			)
			(layer "F.Fab")
		)
		(fp_line
			(start 0.120396 0.3048)
			(end 0.120396 0.2794)
			(stroke
				(width 0.1)
				(type default)
			)
			(layer "F.Fab")
		)
		(fp_line
			(start -0.12065 0.3048)
			(end -0.67945 0.3048)
			(stroke
				(width 0.1)
				(type default)
			)
			(layer "F.Fab")
		)
		(fp_line
			(start -0.67945 0.3048)
			(end -0.67945 -0.305054)
			(stroke
				(width 0.1)
				(type default)
			)
			(layer "F.Fab")
		)
		(pad "1" smd circle
			(at -0.40005 0 90)
			(size 0 0)
			(layers "F.Cu" "F.Mask" "F.Paste")
			(net "PRSNT_NIC0_R_N")
		)
		(pad "2" smd circle
			(at 0.40005 0 90)
			(size 0 0)
			(layers "F.Cu" "F.Mask" "F.Paste")
			(net "PRSNT_NIC0_N")
		)
	)
	(footprint ""
		(layer "F.Cu")
		(at 240.86439 -253.983998 -90)
		(property "Reference" "C4343"
			(at 0 0 270)
			(layer "F.SilkS")
			(hide yes)
			(effects
				(font
					(size 1.27 1.27)
				)
			)
		)
		(property "Value" ""
			(at 0 0 270)
			(layer "F.Fab")
			(effects
				(font
					(size 1.27 1.27)
				)
			)
		)
		(duplicate_pad_numbers_are_jumpers no)
		(fp_line
			(start -1.524 0.762)
			(end -1.524 -0.762)
			(stroke
				(width 0.1524)
				(type default)
			)
			(layer "F.SilkS")
		)
		(fp_line
			(start 1.524 0.762)
			(end -1.524 0.762)
			(stroke
				(width 0.1524)
				(type default)
			)
			(layer "F.SilkS")
		)
		(fp_line
			(start -1.524 -0.762)
			(end 1.524 -0.762)
			(stroke
				(width 0.1524)
				(type default)
			)
			(layer "F.SilkS")
		)
		(fp_line
			(start 1.524 -0.762)
			(end 1.524 0.762)
			(stroke
				(width 0.1524)
				(type default)
			)
			(layer "F.SilkS")
		)
		(fp_line
			(start -1.1049 0.724916)
			(end 1.1049 0.724916)
			(stroke
				(width 0.1)
				(type default)
			)
			(layer "F.Fab")
		)
		(fp_line
			(start 1.1049 0.724916)
			(end 1.1049 -0.724916)
			(stroke
				(width 0.1)
				(type default)
			)
			(layer "F.Fab")
		)
		(fp_line
			(start -1.1049 -0.724916)
			(end -1.1049 0.724916)
			(stroke
				(width 0.1)
				(type default)
			)
			(layer "F.Fab")
		)
		(fp_line
			(start 1.1049 -0.724916)
			(end -1.1049 -0.724916)
			(stroke
				(width 0.1)
				(type default)
			)
			(layer "F.Fab")
		)
		(pad "1" smd rect
			(at -0.889 0 90)
			(size 1.016 1.27)
			(layers "F.Cu" "F.Mask" "F.Paste")
			(net "P1V25_SERDES_VDDPLL_PEX2_C5")
		)
		(pad "2" smd rect
			(at 0.889 0 90)
			(size 1.016 1.27)
			(layers "F.Cu" "F.Mask" "F.Paste")
			(net "GND")
		)
		(zone
			(layer "F.Cu")
			(hatch none 0.5)
			(connect_pads
				(clearance 0)
			)
			(min_thickness 0.25)
			(keepout
				(tracks not_allowed)
				(vias allowed)
				(pads allowed)
				(copperpour not_allowed)
				(footprints allowed)
			)
			(placement
				(enabled no)
				(sheetname "")
			)
			(fill
				(thermal_gap 0.5)
				(thermal_bridge_width 0.5)
				(island_removal_mode 0)
			)
			(polygon
				(pts
					(xy 241.589306 -254.314198) (xy 240.139474 -254.314198) (xy 240.139474 -253.653798) (xy 241.589306 -253.653798)
				)
			)
		)
	)
	(footprint ""
		(layer "F.Cu")
		(at 13.387578 -275.505164 180)
		(property "Reference" "U87"
			(at -0.61976 -4.369562 0)
			(unlocked yes)
			(layer "F.SilkS")
			(effects
				(font
					(size 0.7874 0.5842)
					(thickness 0.1524)
				)
			)
		)
		(property "Value" ""
			(at 0 0 180)
			(layer "F.Fab")
			(effects
				(font
					(size 1.27 1.27)
				)
			)
		)
		(duplicate_pad_numbers_are_jumpers no)
		(fp_line
			(start 1.500124 1.500124)
			(end 1.004062 1.500124)
			(stroke
				(width 0.1524)
				(type default)
			)
			(layer "F.SilkS")
		)
		(fp_line
			(start 1.500124 1.004062)
			(end 1.500124 1.500124)
			(stroke
				(width 0.1524)
				(type default)
			)
			(layer "F.SilkS")
		)
		(fp_line
			(start 1.500124 -1.500124)
			(end 1.500124 -1.004062)
			(stroke
				(width 0.1524)
				(type default)
			)
			(layer "F.SilkS")
		)
		(fp_line
			(start 1.004062 -1.500124)
			(end 1.500124 -1.500124)
			(stroke
				(width 0.1524)
				(type default)
			)
			(layer "F.SilkS")
		)
		(fp_line
			(start -1.004062 1.500124)
			(end -1.500124 1.500124)
			(stroke
				(width 0.1524)
				(type default)
			)
			(layer "F.SilkS")
		)
		(fp_line
			(start -1.500124 1.500124)
			(end -1.500124 1.004062)
			(stroke
				(width 0.1524)
				(type default)
			)
			(layer "F.SilkS")
		)
		(fp_line
			(start -1.500124 -1.004062)
			(end -1.500124 -1.500124)
			(stroke
				(width 0.1524)
				(type default)
			)
			(layer "F.SilkS")
		)
		(fp_line
			(start -1.500124 -1.500124)
			(end -1.004062 -1.500124)
			(stroke
				(width 0.1524)
				(type default)
			)
			(layer "F.SilkS")
		)
		(fp_poly
			(pts
				(xy -1.954276 -2.075942) (xy -2.672588 -1.357376) (xy -1.59512 -0.99822)
			)
			(stroke
				(width 0)
				(type default)
			)
			(fill yes)
			(layer "F.SilkS")
		)
		(fp_line
			(start 1.500124 1.500124)
			(end -1.500124 1.500124)
			(stroke
				(width 0.1)
				(type default)
			)
			(layer "F.Fab")
		)
		(fp_line
			(start 1.500124 -1.500124)
			(end 1.500124 1.500124)
			(stroke
				(width 0.1)
				(type default)
			)
			(layer "F.Fab")
		)
		(fp_line
			(start -1.500124 1.500124)
			(end -1.500124 -1.500124)
			(stroke
				(width 0.1)
				(type default)
			)
			(layer "F.Fab")
		)
		(fp_line
			(start -1.500124 -1.500124)
			(end 1.500124 -1.500124)
			(stroke
				(width 0.1)
				(type default)
			)
			(layer "F.Fab")
		)
		(fp_poly
			(pts
				(xy -2.847848 -1.258062) (xy -2.847848 -0.242062) (xy -1.831848 -0.750062)
			)
			(stroke
				(width 0)
				(type default)
			)
			(fill yes)
			(layer "F.Fab")
		)
		(pad "1" smd rect
			(at -1.400048 -0.750062 90)
			(size 0.2286 0.6096)
			(layers "F.Cu" "F.Mask" "F.Paste")
			(net "PEX0_P1V25_ADC_A1")
		)
		(pad "2" smd rect
			(at -1.400048 -0.249936 90)
			(size 0.2286 0.6096)
			(layers "F.Cu" "F.Mask" "F.Paste")
			(net "PEX0_P1V25_ADC_A0")
		)
		(pad "3" smd rect
			(at -1.400048 0.249936 90)
			(size 0.2286 0.6096)
			(layers "F.Cu" "F.Mask" "F.Paste")
			(net "PEX0_P1V25_ADC_ALERT_N")
		)
		(pad "4" smd rect
			(at -1.400048 0.750062 90)
			(size 0.2286 0.6096)
			(layers "F.Cu" "F.Mask" "F.Paste")
			(net "SMB_PEX0_P1V25_ADC_SDA")
		)
		(pad "5" smd rect
			(at -0.750062 1.400048 180)
			(size 0.2286 0.6096)
			(layers "F.Cu" "F.Mask" "F.Paste")
			(net "SMB_PEX0_P1V25_ADC_SCL")
		)
		(pad "6" smd rect
			(at -0.249936 1.400048 180)
			(size 0.2286 0.6096)
			(layers "F.Cu" "F.Mask" "F.Paste")
			(net "Net_8618")
		)
		(pad "7" smd rect
			(at 0.249936 1.400048 180)
			(size 0.2286 0.6096)
			(layers "F.Cu" "F.Mask" "F.Paste")
			(net "Net_8617")
		)
		(pad "8" smd rect
			(at 0.750062 1.400048 180)
			(size 0.2286 0.6096)
			(layers "F.Cu" "F.Mask" "F.Paste")
			(net "Net_8616")
		)
		(pad "9" smd rect
			(at 1.400048 0.750062 90)
			(size 0.2286 0.6096)
			(layers "F.Cu" "F.Mask" "F.Paste")
			(net "P3V3_AUX")
		)
		(pad "10" smd rect
			(at 1.400048 0.249936 90)
			(size 0.2286 0.6096)
			(layers "F.Cu" "F.Mask" "F.Paste")
			(net "GND")
		)
		(pad "11" smd rect
			(at 1.400048 -0.249936 90)
			(size 0.2286 0.6096)
			(layers "F.Cu" "F.Mask" "F.Paste")
			(net "P1V25_PEX0_R")
		)
		(pad "12" smd rect
			(at 1.400048 -0.750062 90)
			(size 0.2286 0.6096)
			(layers "F.Cu" "F.Mask" "F.Paste")
			(net "P12V_PEX0_P1V25_VIN_N")
		)
		(pad "13" smd rect
			(at 0.750062 -1.400048 180)
			(size 0.2286 0.6096)
			(layers "F.Cu" "F.Mask" "F.Paste")
			(net "P12V_PEX0_P1V25_VIN_P")
		)
		(pad "14" smd rect
			(at 0.249936 -1.400048 180)
			(size 0.2286 0.6096)
			(layers "F.Cu" "F.Mask" "F.Paste")
			(net "Net_8615")
		)
		(pad "15" smd rect
			(at -0.249936 -1.400048 180)
			(size 0.2286 0.6096)
			(layers "F.Cu" "F.Mask" "F.Paste")
			(net "Net_8614")
		)
		(pad "16" smd rect
			(at -0.750062 -1.400048 180)
			(size 0.2286 0.6096)
			(layers "F.Cu" "F.Mask" "F.Paste")
			(net "Net_8613")
		)
		(pad "TH" smd rect
			(at 0 0 180)
			(size 1.7018 1.7018)
			(layers "F.Cu" "F.Mask" "F.Paste")
			(net "GND")
		)
	)
)
